# T6G (Grand Teton) — schematic netlist excerpt (pin names and nets, part order shuffled) for the footprints in the layout excerpt that follows; sources: Cadence DE-HDL packaged netlist, KiCad conversion of 04192023_DAF0TMB3IC0_F0TG_MB_C_brd_V02_OCP.brd

R2794  Q_RES  4.7K 5% CHIP  pkg 0402LF  page 240 : A = P3V3_AUX ; B = FM_PDB_BUF_EN_R1
C1870  Q_CAP  0.1UF 25V 10% X7R  pkg 0402  page 113 : A = P2E_MB_BMC_TX_BUF_DP<0> ; B = P2E_MB_BMC_TX_BUF_C_DP<0>
R871  Q_RES  4.7K 5% EMPTY  pkg 0201LF  page 342 : A = P1V8_CPU1_RT_1D ; B = JTAG_TEST_MODE_RT_CPU1_P2

(kicad_pcb
	(version 20260206)
	(generator "pcbnew")
	(generator_version "10.0")
	(general
		(thickness 1.6)
		(legacy_teardrops no)
	)
	(paper "A4")
	(title_block
		(title "04192023_DAF0TMB3IC0_F0TG_MB_C_brd_V02_OCP.brd")
		(comment 1 "Grand Teton / footprints 3280-3282 of 8354")
	)
	(layers
		(0 "F.Cu" signal "TOP")
		(4 "In1.Cu" signal "GND")
		(6 "In2.Cu" signal "IN1")
		(8 "In3.Cu" signal "GND1")
		(10 "In4.Cu" signal "IN2")
		(12 "In5.Cu" signal "GND2")
		(14 "In6.Cu" signal "IN3")
		(16 "In7.Cu" signal "GND3")
		(18 "In8.Cu" signal "VCC")
		(20 "In9.Cu" signal "VCC1")
		(22 "In10.Cu" signal "GND4")
		(24 "In11.Cu" signal "IN4")
		(26 "In12.Cu" signal "GND5")
		(28 "In13.Cu" signal "IN5")
		(30 "In14.Cu" signal "GND6")
		(32 "In15.Cu" signal "IN6")
		(34 "In16.Cu" signal "GND7")
		(2 "B.Cu" signal "BOTTOM")
		(9 "F.Adhes" user "F.Adhesive")
		(11 "B.Adhes" user "B.Adhesive")
		(13 "F.Paste" user "Package Geometry/Pastemask Top")
		(15 "B.Paste" user "Package Geometry/Pastemask Bottom")
		(5 "F.SilkS" user "Ref Des/Silkscreen Top")
		(7 "B.SilkS" user "Ref Des/Silkscreen Bottom")
		(1 "F.Mask" user "Board Geometry/Soldermask Top")
		(3 "B.Mask" user "Board Geometry/Soldermask Bottom")
		(17 "Dwgs.User" user "User.Drawings")
		(19 "Cmts.User" user "User.Comments")
		(21 "Eco1.User" user "User.Eco1")
		(23 "Eco2.User" user "User.Eco2")
		(25 "Edge.Cuts" user "Board Geometry/Outline")
		(27 "Margin" user)
		(31 "F.CrtYd" user "Package Geometry/Place Bound Top")
		(29 "B.CrtYd" user "Package Geometry/Place Bound Bottom")
		(35 "F.Fab" user "Ref Des/Assembly Top")
		(33 "B.Fab" user "Ref Des/Assembly Bottom")
	)
	(footprint ""
		(layer "F.Cu")
		(at 28.5369 -421.069008 180)
		(property "Reference" "C1870"
			(at 0 0 180)
			(layer "F.SilkS")
			(hide yes)
			(effects
				(font
					(size 1.27 1.27)
				)
			)
		)
		(property "Value" ""
			(at 0 0 180)
			(layer "F.Fab")
			(effects
				(font
					(size 1.27 1.27)
				)
			)
		)
		(duplicate_pad_numbers_are_jumpers no)
		(fp_line
			(start 0.7874 -0.4064)
			(end 0.7874 0.215392)
			(stroke
				(width 0.1524)
				(type default)
			)
			(layer "F.SilkS")
		)
		(fp_line
			(start -0.3429 0.4064)
			(end -0.7874 0.4064)
			(stroke
				(width 0.1524)
				(type default)
			)
			(layer "F.SilkS")
		)
		(fp_line
			(start -0.7874 -0.4064)
			(end 0.7874 -0.4064)
			(stroke
				(width 0.1524)
				(type default)
			)
			(layer "F.SilkS")
		)
		(fp_line
			(start 0.6858 0.3048)
			(end 0.1016 0.3048)
			(stroke
				(width 0.1)
				(type default)
			)
			(layer "F.Fab")
		)
		(fp_line
			(start 0.6858 -0.3048)
			(end 0.6858 0.3048)
			(stroke
				(width 0.1)
				(type default)
			)
			(layer "F.Fab")
		)
		(fp_line
			(start 0.1016 0.3048)
			(end 0.1016 0.2794)
			(stroke
				(width 0.1)
				(type default)
			)
			(layer "F.Fab")
		)
		(fp_line
			(start 0.1016 0.2794)
			(end -0.1016 0.2794)
			(stroke
				(width 0.1)
				(type default)
			)
			(layer "F.Fab")
		)
		(fp_line
			(start 0.1016 -0.2794)
			(end 0.1016 -0.3048)
			(stroke
				(width 0.1)
				(type default)
			)
			(layer "F.Fab")
		)
		(fp_line
			(start 0.1016 -0.3048)
			(end 0.6858 -0.3048)
			(stroke
				(width 0.1)
				(type default)
			)
			(layer "F.Fab")
		)
		(fp_line
			(start -0.1016 0.3048)
			(end -0.6858 0.3048)
			(stroke
				(width 0.1)
				(type default)
			)
			(layer "F.Fab")
		)
		(fp_line
			(start -0.1016 0.2794)
			(end -0.1016 0.3048)
			(stroke
				(width 0.1)
				(type default)
			)
			(layer "F.Fab")
		)
		(fp_line
			(start -0.1016 -0.2794)
			(end 0.1016 -0.2794)
			(stroke
				(width 0.1)
				(type default)
			)
			(layer "F.Fab")
		)
		(fp_line
			(start -0.1016 -0.3048)
			(end -0.1016 -0.2794)
			(stroke
				(width 0.1)
				(type default)
			)
			(layer "F.Fab")
		)
		(fp_line
			(start -0.6858 0.3048)
			(end -0.6858 -0.3048)
			(stroke
				(width 0.1)
				(type default)
			)
			(layer "F.Fab")
		)
		(fp_line
			(start -0.6858 -0.3048)
			(end -0.1016 -0.3048)
			(stroke
				(width 0.1)
				(type default)
			)
			(layer "F.Fab")
		)
		(pad "1" smd rect
			(at -0.40005 0)
			(size 0.4572 0.508)
			(layers "F.Cu" "F.Mask" "F.Paste")
			(net "P2E_MB_BMC_TX_BUF_DP<0>")
		)
		(pad "2" smd rect
			(at 0.40005 0)
			(size 0.4572 0.508)
			(layers "F.Cu" "F.Mask" "F.Paste")
			(net "P2E_MB_BMC_TX_BUF_C_DP<0>")
		)
	)
	(footprint ""
		(layer "F.Cu")
		(at 191.055498 -425.829476 -90)
		(property "Reference" "R2794"
			(at 0 0 270)
			(layer "F.SilkS")
			(hide yes)
			(effects
				(font
					(size 1.27 1.27)
				)
			)
		)
		(property "Value" ""
			(at 0 0 270)
			(layer "F.Fab")
			(effects
				(font
					(size 1.27 1.27)
				)
			)
		)
		(duplicate_pad_numbers_are_jumpers no)
		(fp_line
			(start -0.7874 0.4064)
			(end -0.7874 -0.4064)
			(stroke
				(width 0.1524)
				(type default)
			)
			(layer "F.SilkS")
		)
		(fp_line
			(start 0.7874 0.4064)
			(end -0.7874 0.4064)
			(stroke
				(width 0.1524)
				(type default)
			)
			(layer "F.SilkS")
		)
		(fp_line
			(start -0.7874 -0.4064)
			(end 0.7874 -0.4064)
			(stroke
				(width 0.1524)
				(type default)
			)
			(layer "F.SilkS")
		)
		(fp_line
			(start 0.7874 -0.4064)
			(end 0.7874 0.4064)
			(stroke
				(width 0.1524)
				(type default)
			)
			(layer "F.SilkS")
		)
		(fp_line
			(start -0.67945 0.3048)
			(end -0.67945 -0.305054)
			(stroke
				(width 0.1)
				(type default)
			)
			(layer "F.Fab")
		)
		(fp_line
			(start -0.12065 0.3048)
			(end -0.67945 0.3048)
			(stroke
				(width 0.1)
				(type default)
			)
			(layer "F.Fab")
		)
		(fp_line
			(start 0.120396 0.3048)
			(end 0.120396 0.2794)
			(stroke
				(width 0.1)
				(type default)
			)
			(layer "F.Fab")
		)
		(fp_line
			(start 0.67945 0.3048)
			(end 0.120396 0.3048)
			(stroke
				(width 0.1)
				(type default)
			)
			(layer "F.Fab")
		)
		(fp_line
			(start -0.12065 0.2794)
			(end -0.12065 0.3048)
			(stroke
				(width 0.1)
				(type default)
			)
			(layer "F.Fab")
		)
		(fp_line
			(start 0.120396 0.2794)
			(end -0.12065 0.2794)
			(stroke
				(width 0.1)
				(type default)
			)
			(layer "F.Fab")
		)
		(fp_line
			(start -0.12065 -0.2794)
			(end 0.12065 -0.2794)
			(stroke
				(width 0.1)
				(type default)
			)
			(layer "F.Fab")
		)
		(fp_line
			(start 0.12065 -0.2794)
			(end 0.12065 -0.3048)
			(stroke
				(width 0.1)
				(type default)
			)
			(layer "F.Fab")
		)
		(fp_line
			(start 0.12065 -0.3048)
			(end 0.67945 -0.3048)
			(stroke
				(width 0.1)
				(type default)
			)
			(layer "F.Fab")
		)
		(fp_line
			(start 0.67945 -0.3048)
			(end 0.67945 0.3048)
			(stroke
				(width 0.1)
				(type default)
			)
			(layer "F.Fab")
		)
		(fp_line
			(start -0.67945 -0.305054)
			(end -0.12065 -0.305054)
			(stroke
				(width 0.1)
				(type default)
			)
			(layer "F.Fab")
		)
		(fp_line
			(start -0.12065 -0.305054)
			(end -0.12065 -0.2794)
			(stroke
				(width 0.1)
				(type default)
			)
			(layer "F.Fab")
		)
		(pad "1" smd circle
			(at -0.40005 0 270)
			(size 0 0)
			(layers "F.Cu" "F.Mask" "F.Paste")
			(net "P3V3_AUX")
		)
		(pad "2" smd circle
			(at 0.40005 0 270)
			(size 0 0)
			(layers "F.Cu" "F.Mask" "F.Paste")
			(net "FM_PDB_BUF_EN_R1")
		)
	)
	(footprint ""
		(layer "F.Cu")
		(at 146.214846 -396.491206 -90)
		(property "Reference" "R871"
			(at 0 0 270)
			(layer "F.SilkS")
			(hide yes)
			(effects
				(font
					(size 1.27 1.27)
				)
			)
		)
		(property "Value" ""
			(at 0 0 270)
			(layer "F.Fab")
			(effects
				(font
					(size 1.27 1.27)
				)
			)
		)
		(duplicate_pad_numbers_are_jumpers no)
		(fp_line
			(start -0.32512 0.175006)
			(end -0.32512 -0.175006)
			(stroke
				(width 0.1)
				(type default)
			)
			(layer "F.Fab")
		)
		(fp_line
			(start 0.32512 0.175006)
			(end -0.32512 0.175006)
			(stroke
				(width 0.1)
				(type default)
			)
			(layer "F.Fab")
		)
		(fp_line
			(start -0.32512 -0.175006)
			(end 0.32512 -0.175006)
			(stroke
				(width 0.1)
				(type default)
			)
			(layer "F.Fab")
		)
		(fp_line
			(start 0.32512 -0.175006)
			(end 0.32512 0.175006)
			(stroke
				(width 0.1)
				(type default)
			)
			(layer "F.Fab")
		)
		(pad "1" smd rect
			(at -0.2667 0 270)
			(size 0.3048 0.381)
			(layers "F.Cu" "F.Mask" "F.Paste")
			(net "P1V8_CPU1_RT_1D")
		)
		(pad "2" smd rect
			(at 0.2667 0 90)
			(size 0.3048 0.381)
			(layers "F.Cu" "F.Mask" "F.Paste")
			(net "JTAG_TEST_MODE_RT_CPU1_P2")
		)
	)
)
